# T6G (Grand Teton) — schematic netlist excerpt (pin names and nets, part order shuffled) for the footprints in the layout excerpt that follows; sources: Cadence DE-HDL packaged netlist, KiCad conversion of 04192023_DAF0TMB3IC0_F0TG_MB_C_brd_V02_OCP.brd

R644  Q_RES  10K 5% CHIP  pkg 0402LF  page 361 : A = P3V3_AUX ; B = PWRGD_P1V8_RETIMER_CPU1
C6555  Q_CAP_DIFFBUS  DIFF BUS_0.22UF 6.3V 20% X6S  pkg C0201  page 286 : \1\ = P5E_CPU0_P1_TX_BUF_C_DP<11> ; \2\ = P5E_CPU0_P1_TX_BUF_DP<11>
PR6606  Q_RES  0 5% CHIP  pkg 0402LF  page 362 : A = P12V_AUX ; B = P0V9_RETIMER_CPU0_VINSEN

(kicad_pcb
	(version 20260206)
	(generator "pcbnew")
	(generator_version "10.0")
	(general
		(thickness 1.6)
		(legacy_teardrops no)
	)
	(paper "A4")
	(title_block
		(title "04192023_DAF0TMB3IC0_F0TG_MB_C_brd_V02_OCP.brd")
		(comment 1 "Grand Teton / footprints 6043-6045 of 8354")
	)
	(layers
		(0 "F.Cu" signal "TOP")
		(4 "In1.Cu" signal "GND")
		(6 "In2.Cu" signal "IN1")
		(8 "In3.Cu" signal "GND1")
		(10 "In4.Cu" signal "IN2")
		(12 "In5.Cu" signal "GND2")
		(14 "In6.Cu" signal "IN3")
		(16 "In7.Cu" signal "GND3")
		(18 "In8.Cu" signal "VCC")
		(20 "In9.Cu" signal "VCC1")
		(22 "In10.Cu" signal "GND4")
		(24 "In11.Cu" signal "IN4")
		(26 "In12.Cu" signal "GND5")
		(28 "In13.Cu" signal "IN5")
		(30 "In14.Cu" signal "GND6")
		(32 "In15.Cu" signal "IN6")
		(34 "In16.Cu" signal "GND7")
		(2 "B.Cu" signal "BOTTOM")
		(9 "F.Adhes" user "F.Adhesive")
		(11 "B.Adhes" user "B.Adhesive")
		(13 "F.Paste" user "Package Geometry/Pastemask Top")
		(15 "B.Paste" user "Package Geometry/Pastemask Bottom")
		(5 "F.SilkS" user "Ref Des/Silkscreen Top")
		(7 "B.SilkS" user "Ref Des/Silkscreen Bottom")
		(1 "F.Mask" user "Board Geometry/Soldermask Top")
		(3 "B.Mask" user "Board Geometry/Soldermask Bottom")
		(17 "Dwgs.User" user "User.Drawings")
		(19 "Cmts.User" user "User.Comments")
		(21 "Eco1.User" user "User.Eco1")
		(23 "Eco2.User" user "User.Eco2")
		(25 "Edge.Cuts" user "Board Geometry/Outline")
		(27 "Margin" user)
		(31 "F.CrtYd" user "Package Geometry/Place Bound Top")
		(29 "B.CrtYd" user "Package Geometry/Place Bound Bottom")
		(35 "F.Fab" user "Ref Des/Assembly Top")
		(33 "B.Fab" user "Ref Des/Assembly Bottom")
	)
	(footprint ""
		(layer "B.Cu")
		(at 449.646802 -425.92371)
		(property "Reference" "PR6606"
			(at 0 0 0)
			(layer "B.SilkS")
			(hide yes)
			(effects
				(font
					(size 1.27 1.27)
				)
				(justify mirror)
			)
		)
		(property "Value" ""
			(at 0 0 0)
			(layer "B.Fab")
			(effects
				(font
					(size 1.27 1.27)
				)
				(justify mirror)
			)
		)
		(duplicate_pad_numbers_are_jumpers no)
		(fp_line
			(start -0.7874 -0.4064)
			(end -0.7874 0.4064)
			(stroke
				(width 0.1524)
				(type default)
			)
			(layer "B.SilkS")
		)
		(fp_line
			(start -0.7874 0.4064)
			(end 0.7874 0.4064)
			(stroke
				(width 0.1524)
				(type default)
			)
			(layer "B.SilkS")
		)
		(fp_line
			(start 0.7874 -0.4064)
			(end -0.7874 -0.4064)
			(stroke
				(width 0.1524)
				(type default)
			)
			(layer "B.SilkS")
		)
		(fp_line
			(start 0.7874 0.4064)
			(end 0.7874 -0.4064)
			(stroke
				(width 0.1524)
				(type default)
			)
			(layer "B.SilkS")
		)
		(fp_line
			(start -0.67945 -0.3048)
			(end -0.67945 0.3048)
			(stroke
				(width 0.1)
				(type default)
			)
			(layer "B.Fab")
		)
		(fp_line
			(start -0.67945 0.3048)
			(end -0.120396 0.3048)
			(stroke
				(width 0.1)
				(type default)
			)
			(layer "B.Fab")
		)
		(fp_line
			(start -0.12065 -0.3048)
			(end -0.67945 -0.3048)
			(stroke
				(width 0.1)
				(type default)
			)
			(layer "B.Fab")
		)
		(fp_line
			(start -0.12065 -0.2794)
			(end -0.12065 -0.3048)
			(stroke
				(width 0.1)
				(type default)
			)
			(layer "B.Fab")
		)
		(fp_line
			(start -0.120396 0.2794)
			(end 0.12065 0.2794)
			(stroke
				(width 0.1)
				(type default)
			)
			(layer "B.Fab")
		)
		(fp_line
			(start -0.120396 0.3048)
			(end -0.120396 0.2794)
			(stroke
				(width 0.1)
				(type default)
			)
			(layer "B.Fab")
		)
		(fp_line
			(start 0.12065 -0.305054)
			(end 0.12065 -0.2794)
			(stroke
				(width 0.1)
				(type default)
			)
			(layer "B.Fab")
		)
		(fp_line
			(start 0.12065 -0.2794)
			(end -0.12065 -0.2794)
			(stroke
				(width 0.1)
				(type default)
			)
			(layer "B.Fab")
		)
		(fp_line
			(start 0.12065 0.2794)
			(end 0.12065 0.3048)
			(stroke
				(width 0.1)
				(type default)
			)
			(layer "B.Fab")
		)
		(fp_line
			(start 0.12065 0.3048)
			(end 0.67945 0.3048)
			(stroke
				(width 0.1)
				(type default)
			)
			(layer "B.Fab")
		)
		(fp_line
			(start 0.67945 -0.305054)
			(end 0.12065 -0.305054)
			(stroke
				(width 0.1)
				(type default)
			)
			(layer "B.Fab")
		)
		(fp_line
			(start 0.67945 0.3048)
			(end 0.67945 -0.305054)
			(stroke
				(width 0.1)
				(type default)
			)
			(layer "B.Fab")
		)
		(pad "1" smd circle
			(at 0.40005 0 180)
			(size 0 0)
			(layers "B.Cu" "B.Mask" "B.Paste")
			(net "P12V_AUX")
		)
		(pad "2" smd circle
			(at -0.40005 0 180)
			(size 0 0)
			(layers "B.Cu" "B.Mask" "B.Paste")
			(net "P0V9_RETIMER_CPU0_VINSEN")
		)
	)
	(footprint ""
		(layer "B.Cu")
		(at 339.910166 -416.899344 90)
		(property "Reference" "C6555"
			(at 0 0 90)
			(layer "B.SilkS")
			(hide yes)
			(effects
				(font
					(size 1.27 1.27)
				)
				(justify mirror)
			)
		)
		(property "Value" ""
			(at 0 0 90)
			(layer "B.Fab")
			(effects
				(font
					(size 1.27 1.27)
				)
				(justify mirror)
			)
		)
		(duplicate_pad_numbers_are_jumpers no)
		(fp_line
			(start 0.299974 -0.150114)
			(end -0.299974 -0.150114)
			(stroke
				(width 0.1)
				(type default)
			)
			(layer "B.Fab")
		)
		(fp_line
			(start -0.299974 -0.150114)
			(end -0.299974 0.150114)
			(stroke
				(width 0.1)
				(type default)
			)
			(layer "B.Fab")
		)
		(fp_line
			(start 0.299974 0.150114)
			(end 0.299974 -0.150114)
			(stroke
				(width 0.1)
				(type default)
			)
			(layer "B.Fab")
		)
		(fp_line
			(start -0.299974 0.150114)
			(end 0.299974 0.150114)
			(stroke
				(width 0.1)
				(type default)
			)
			(layer "B.Fab")
		)
		(pad "1" smd rect
			(at 0.2667 0 270)
			(size 0.3048 0.381)
			(layers "B.Cu" "B.Mask" "B.Paste")
			(net "P5E_CPU0_P1_TX_BUF_C_DP<11>")
		)
		(pad "2" smd rect
			(at -0.2667 0 270)
			(size 0.3048 0.381)
			(layers "B.Cu" "B.Mask" "B.Paste")
			(net "P5E_CPU0_P1_TX_BUF_DP<11>")
		)
	)
	(footprint ""
		(layer "B.Cu")
		(at 226.366578 -290.844732 180)
		(property "Reference" "R644"
			(at 0 0 0)
			(layer "B.SilkS")
			(hide yes)
			(effects
				(font
					(size 1.27 1.27)
				)
				(justify mirror)
			)
		)
		(property "Value" ""
			(at 0 0 0)
			(layer "B.Fab")
			(effects
				(font
					(size 1.27 1.27)
				)
				(justify mirror)
			)
		)
		(duplicate_pad_numbers_are_jumpers no)
		(fp_line
			(start 0.7874 0.4064)
			(end 0.7874 -0.4064)
			(stroke
				(width 0.1524)
				(type default)
			)
			(layer "B.SilkS")
		)
		(fp_line
			(start 0.7874 -0.4064)
			(end -0.7874 -0.4064)
			(stroke
				(width 0.1524)
				(type default)
			)
			(layer "B.SilkS")
		)
		(fp_line
			(start -0.7874 0.4064)
			(end 0.7874 0.4064)
			(stroke
				(width 0.1524)
				(type default)
			)
			(layer "B.SilkS")
		)
		(fp_line
			(start -0.7874 -0.4064)
			(end -0.7874 0.4064)
			(stroke
				(width 0.1524)
				(type default)
			)
			(layer "B.SilkS")
		)
		(fp_line
			(start 0.67945 0.3048)
			(end 0.67945 -0.305054)
			(stroke
				(width 0.1)
				(type default)
			)
			(layer "B.Fab")
		)
		(fp_line
			(start 0.67945 -0.305054)
			(end 0.12065 -0.305054)
			(stroke
				(width 0.1)
				(type default)
			)
			(layer "B.Fab")
		)
		(fp_line
			(start 0.12065 0.3048)
			(end 0.67945 0.3048)
			(stroke
				(width 0.1)
				(type default)
			)
			(layer "B.Fab")
		)
		(fp_line
			(start 0.12065 0.2794)
			(end 0.12065 0.3048)
			(stroke
				(width 0.1)
				(type default)
			)
			(layer "B.Fab")
		)
		(fp_line
			(start 0.12065 -0.2794)
			(end -0.12065 -0.2794)
			(stroke
				(width 0.1)
				(type default)
			)
			(layer "B.Fab")
		)
		(fp_line
			(start 0.12065 -0.305054)
			(end 0.12065 -0.2794)
			(stroke
				(width 0.1)
				(type default)
			)
			(layer "B.Fab")
		)
		(fp_line
			(start -0.120396 0.3048)
			(end -0.120396 0.2794)
			(stroke
				(width 0.1)
				(type default)
			)
			(layer "B.Fab")
		)
		(fp_line
			(start -0.120396 0.2794)
			(end 0.12065 0.2794)
			(stroke
				(width 0.1)
				(type default)
			)
			(layer "B.Fab")
		)
		(fp_line
			(start -0.12065 -0.2794)
			(end -0.12065 -0.3048)
			(stroke
				(width 0.1)
				(type default)
			)
			(layer "B.Fab")
		)
		(fp_line
			(start -0.12065 -0.3048)
			(end -0.67945 -0.3048)
			(stroke
				(width 0.1)
				(type default)
			)
			(layer "B.Fab")
		)
		(fp_line
			(start -0.67945 0.3048)
			(end -0.120396 0.3048)
			(stroke
				(width 0.1)
				(type default)
			)
			(layer "B.Fab")
		)
		(fp_line
			(start -0.67945 -0.3048)
			(end -0.67945 0.3048)
			(stroke
				(width 0.1)
				(type default)
			)
			(layer "B.Fab")
		)
		(pad "1" smd circle
			(at 0.40005 0)
			(size 0 0)
			(layers "B.Cu" "B.Mask" "B.Paste")
			(net "P3V3_AUX")
		)
		(pad "2" smd circle
			(at -0.40005 0)
			(size 0 0)
			(layers "B.Cu" "B.Mask" "B.Paste")
			(net "PWRGD_P1V8_RETIMER_CPU1")
		)
	)
)
